FILE_TYPE = MULTI_PHYS_TABLE;

PART 'CONN8_210HP1080BR1'

{========================================================================================}
:VALUE                  | PART_TYPE | MATERIAL | PART_NUMBER    = STANDARD | LIFECYCLE      | PART_NUMBER   | JEDEC_TYPE    | DESCRIPTION                            | MANUFTR | MANUF_PN         | RD_CMPLS_LVL | CMPLS_LVL | CLASS | DIP_SMD | FROM_PJ      | DATA                     | FP_ECN | EE_CHECK_LIST | CREATOR | CREATEDAY  | PSL | STATUS | ESD_CDM | ESD_HBM | ESD_MM | MSD | PIN_LENGTH_LONG_PIN | PIN_LENGTH_SHORT_PIN ;
{========================================================================================}
 'CONN8_210-HP1-080BR1' | 'THLF'    | 'IO'     | 'DFHD08MS392'(!) = ''       | ''               | 'DFHD08MS392' |'HEADER1X8XE'| 'CONN DIP HEADER 8P 1R MS(P2.54,H8.6)' | 'PRX'   | '210-HP1-080BR1' | 'EP(V1)'     | 'EP(V1)'  | 'IO'  | 'DIP'   | 'F08-SHERRY' | 'PRX_210-HP1-080BR1.pdf' | ''     | ''            | ''      | '20160406' | ''  | ''     | ''      | ''      | ''     | ''  | '119 MILS'          | '119 MILS'          
 'CONN8_210-HP1-080BR1' | 'THLF'    | 'EMPTY'  | 'DFHD08MS392'(!) = ''       | ''               | 'DFHD08MS392' |'HEADER1X8XE'| 'CONN DIP HEADER 8P 1R MS(P2.54,H8.6)' | 'PRX'   | '210-HP1-080BR1' | 'EP(V1)'     | 'EP(V1)'  | 'IO'  | 'DIP'   | 'F08-SHERRY' | 'PRX_210-HP1-080BR1.pdf' | ''     | ''            | ''      | '20160406' | ''  | ''     | ''      | ''      | ''     | ''  | '119 MILS'          | '119 MILS'          

END_PART

END.

